# T6G (Grand Teton) — schematic netlist excerpt (pin names and nets, part order shuffled) for the footprints in the layout excerpt that follows; sources: Cadence DE-HDL packaged netlist, KiCad conversion of 04192023_DAF0TMB3IC0_F0TG_MB_C_brd_V02_OCP.brd

C1963  Q_CAP  0.1UF 25V 10% X7R  pkg 0402  page 129 : A = P3V3_AUX ; B = GND
R3170  Q_RES  0 5% CHIP  pkg 0402LF  page 137 : A = OCP_V3_2_ISO_BIF1_EN ; B = OCP_V3_2_BIF1_R_N

(kicad_pcb
	(version 20260206)
	(generator "pcbnew")
	(generator_version "10.0")
	(general
		(thickness 1.6)
		(legacy_teardrops no)
	)
	(paper "A4")
	(title_block
		(title "04192023_DAF0TMB3IC0_F0TG_MB_C_brd_V02_OCP.brd")
		(comment 1 "Grand Teton / footprints 2852-2853 of 8354")
	)
	(layers
		(0 "F.Cu" signal "TOP")
		(4 "In1.Cu" signal "GND")
		(6 "In2.Cu" signal "IN1")
		(8 "In3.Cu" signal "GND1")
		(10 "In4.Cu" signal "IN2")
		(12 "In5.Cu" signal "GND2")
		(14 "In6.Cu" signal "IN3")
		(16 "In7.Cu" signal "GND3")
		(18 "In8.Cu" signal "VCC")
		(20 "In9.Cu" signal "VCC1")
		(22 "In10.Cu" signal "GND4")
		(24 "In11.Cu" signal "IN4")
		(26 "In12.Cu" signal "GND5")
		(28 "In13.Cu" signal "IN5")
		(30 "In14.Cu" signal "GND6")
		(32 "In15.Cu" signal "IN6")
		(34 "In16.Cu" signal "GND7")
		(2 "B.Cu" signal "BOTTOM")
		(9 "F.Adhes" user "F.Adhesive")
		(11 "B.Adhes" user "B.Adhesive")
		(13 "F.Paste" user "Package Geometry/Pastemask Top")
		(15 "B.Paste" user "Package Geometry/Pastemask Bottom")
		(5 "F.SilkS" user "Ref Des/Silkscreen Top")
		(7 "B.SilkS" user "Ref Des/Silkscreen Bottom")
		(1 "F.Mask" user "Board Geometry/Soldermask Top")
		(3 "B.Mask" user "Board Geometry/Soldermask Bottom")
		(17 "Dwgs.User" user "User.Drawings")
		(19 "Cmts.User" user "User.Comments")
		(21 "Eco1.User" user "User.Eco1")
		(23 "Eco2.User" user "User.Eco2")
		(25 "Edge.Cuts" user "Board Geometry/Outline")
		(27 "Margin" user)
		(31 "F.CrtYd" user "Package Geometry/Place Bound Top")
		(29 "B.CrtYd" user "Package Geometry/Place Bound Bottom")
		(35 "F.Fab" user "Ref Des/Assembly Top")
		(33 "B.Fab" user "Ref Des/Assembly Bottom")
	)
	(footprint ""
		(layer "F.Cu")
		(at 105.918 -423.291 90)
		(property "Reference" "C1963"
			(at 0 0 90)
			(layer "F.SilkS")
			(hide yes)
			(effects
				(font
					(size 1.27 1.27)
				)
			)
		)
		(property "Value" ""
			(at 0 0 90)
			(layer "F.Fab")
			(effects
				(font
					(size 1.27 1.27)
				)
			)
		)
		(duplicate_pad_numbers_are_jumpers no)
		(fp_line
			(start 0.7874 -0.4064)
			(end 0.7874 0.4064)
			(stroke
				(width 0.1524)
				(type default)
			)
			(layer "F.SilkS")
		)
		(fp_line
			(start -0.7874 -0.4064)
			(end 0.7874 -0.4064)
			(stroke
				(width 0.1524)
				(type default)
			)
			(layer "F.SilkS")
		)
		(fp_line
			(start 0.7874 0.4064)
			(end -0.7874 0.4064)
			(stroke
				(width 0.1524)
				(type default)
			)
			(layer "F.SilkS")
		)
		(fp_line
			(start -0.7874 0.4064)
			(end -0.7874 -0.4064)
			(stroke
				(width 0.1524)
				(type default)
			)
			(layer "F.SilkS")
		)
		(fp_line
			(start -0.12065 -0.305054)
			(end -0.12065 -0.2794)
			(stroke
				(width 0.1)
				(type default)
			)
			(layer "F.Fab")
		)
		(fp_line
			(start -0.67945 -0.305054)
			(end -0.12065 -0.305054)
			(stroke
				(width 0.1)
				(type default)
			)
			(layer "F.Fab")
		)
		(fp_line
			(start 0.67945 -0.3048)
			(end 0.67945 0.3048)
			(stroke
				(width 0.1)
				(type default)
			)
			(layer "F.Fab")
		)
		(fp_line
			(start 0.12065 -0.3048)
			(end 0.67945 -0.3048)
			(stroke
				(width 0.1)
				(type default)
			)
			(layer "F.Fab")
		)
		(fp_line
			(start 0.12065 -0.2794)
			(end 0.12065 -0.3048)
			(stroke
				(width 0.1)
				(type default)
			)
			(layer "F.Fab")
		)
		(fp_line
			(start -0.12065 -0.2794)
			(end 0.12065 -0.2794)
			(stroke
				(width 0.1)
				(type default)
			)
			(layer "F.Fab")
		)
		(fp_line
			(start 0.120396 0.2794)
			(end -0.12065 0.2794)
			(stroke
				(width 0.1)
				(type default)
			)
			(layer "F.Fab")
		)
		(fp_line
			(start -0.12065 0.2794)
			(end -0.12065 0.3048)
			(stroke
				(width 0.1)
				(type default)
			)
			(layer "F.Fab")
		)
		(fp_line
			(start 0.67945 0.3048)
			(end 0.120396 0.3048)
			(stroke
				(width 0.1)
				(type default)
			)
			(layer "F.Fab")
		)
		(fp_line
			(start 0.120396 0.3048)
			(end 0.120396 0.2794)
			(stroke
				(width 0.1)
				(type default)
			)
			(layer "F.Fab")
		)
		(fp_line
			(start -0.12065 0.3048)
			(end -0.67945 0.3048)
			(stroke
				(width 0.1)
				(type default)
			)
			(layer "F.Fab")
		)
		(fp_line
			(start -0.67945 0.3048)
			(end -0.67945 -0.305054)
			(stroke
				(width 0.1)
				(type default)
			)
			(layer "F.Fab")
		)
		(pad "1" smd circle
			(at -0.40005 0 90)
			(size 0 0)
			(layers "F.Cu" "F.Mask" "F.Paste")
			(net "P3V3_AUX")
		)
		(pad "2" smd circle
			(at 0.40005 0 90)
			(size 0 0)
			(layers "F.Cu" "F.Mask" "F.Paste")
			(net "GND")
		)
	)
	(footprint ""
		(layer "F.Cu")
		(at 62.043564 -16.220948 -90)
		(property "Reference" "R3170"
			(at 0 0 270)
			(layer "F.SilkS")
			(hide yes)
			(effects
				(font
					(size 1.27 1.27)
				)
			)
		)
		(property "Value" ""
			(at 0 0 270)
			(layer "F.Fab")
			(effects
				(font
					(size 1.27 1.27)
				)
			)
		)
		(duplicate_pad_numbers_are_jumpers no)
		(fp_line
			(start -0.7874 0.4064)
			(end -0.7874 -0.4064)
			(stroke
				(width 0.1524)
				(type default)
			)
			(layer "F.SilkS")
		)
		(fp_line
			(start 0.7874 0.4064)
			(end -0.7874 0.4064)
			(stroke
				(width 0.1524)
				(type default)
			)
			(layer "F.SilkS")
		)
		(fp_line
			(start -0.7874 -0.4064)
			(end 0.7874 -0.4064)
			(stroke
				(width 0.1524)
				(type default)
			)
			(layer "F.SilkS")
		)
		(fp_line
			(start 0.7874 -0.4064)
			(end 0.7874 0.4064)
			(stroke
				(width 0.1524)
				(type default)
			)
			(layer "F.SilkS")
		)
		(fp_line
			(start -0.67945 0.3048)
			(end -0.67945 -0.305054)
			(stroke
				(width 0.1)
				(type default)
			)
			(layer "F.Fab")
		)
		(fp_line
			(start -0.12065 0.3048)
			(end -0.67945 0.3048)
			(stroke
				(width 0.1)
				(type default)
			)
			(layer "F.Fab")
		)
		(fp_line
			(start 0.120396 0.3048)
			(end 0.120396 0.2794)
			(stroke
				(width 0.1)
				(type default)
			)
			(layer "F.Fab")
		)
		(fp_line
			(start 0.67945 0.3048)
			(end 0.120396 0.3048)
			(stroke
				(width 0.1)
				(type default)
			)
			(layer "F.Fab")
		)
		(fp_line
			(start -0.12065 0.2794)
			(end -0.12065 0.3048)
			(stroke
				(width 0.1)
				(type default)
			)
			(layer "F.Fab")
		)
		(fp_line
			(start 0.120396 0.2794)
			(end -0.12065 0.2794)
			(stroke
				(width 0.1)
				(type default)
			)
			(layer "F.Fab")
		)
		(fp_line
			(start -0.12065 -0.2794)
			(end 0.12065 -0.2794)
			(stroke
				(width 0.1)
				(type default)
			)
			(layer "F.Fab")
		)
		(fp_line
			(start 0.12065 -0.2794)
			(end 0.12065 -0.3048)
			(stroke
				(width 0.1)
				(type default)
			)
			(layer "F.Fab")
		)
		(fp_line
			(start 0.12065 -0.3048)
			(end 0.67945 -0.3048)
			(stroke
				(width 0.1)
				(type default)
			)
			(layer "F.Fab")
		)
		(fp_line
			(start 0.67945 -0.3048)
			(end 0.67945 0.3048)
			(stroke
				(width 0.1)
				(type default)
			)
			(layer "F.Fab")
		)
		(fp_line
			(start -0.67945 -0.305054)
			(end -0.12065 -0.305054)
			(stroke
				(width 0.1)
				(type default)
			)
			(layer "F.Fab")
		)
		(fp_line
			(start -0.12065 -0.305054)
			(end -0.12065 -0.2794)
			(stroke
				(width 0.1)
				(type default)
			)
			(layer "F.Fab")
		)
		(pad "1" smd circle
			(at -0.40005 0 270)
			(size 0 0)
			(layers "F.Cu" "F.Mask" "F.Paste")
			(net "OCP_V3_2_ISO_BIF1_EN")
		)
		(pad "2" smd circle
			(at 0.40005 0 270)
			(size 0 0)
			(layers "F.Cu" "F.Mask" "F.Paste")
			(net "OCP_V3_2_BIF1_R_N")
		)
	)
)
